(kicad_pcb
	(version 20260206)
	(generator "pcbnew")
	(generator_version "10.0")
	(general
		(thickness 1.6)
		(legacy_teardrops no)
	)
	(paper "A4")
	(title_block
		(title "timecard-production-celestica-r4006 — R4006-B0001-02_R01.brd")
		(comment 1 "Time Appliance Project (Time Card) / footprints 454-462 of 1113")
	)
	(layers
		(0 "F.Cu" signal "TOP")
		(4 "In1.Cu" signal "L02_GND1")
		(6 "In2.Cu" signal "L03_SIG1")
		(8 "In3.Cu" signal "L04_GND2")
		(10 "In4.Cu" signal "L05_VCC1")
		(12 "In5.Cu" signal "L06_VCC2")
		(14 "In6.Cu" signal "L07_GND3")
		(16 "In7.Cu" signal "L08_SIG2")
		(18 "In8.Cu" signal "L09_GND4")
		(2 "B.Cu" signal "BOTTOM")
		(9 "F.Adhes" user "F.Adhesive")
		(11 "B.Adhes" user "B.Adhesive")
		(13 "F.Paste" user "Package Geometry/Pastemask Top")
		(15 "B.Paste" user "Package Geometry/Pastemask Bottom")
		(5 "F.SilkS" user "Ref Des/Silkscreen Top")
		(7 "B.SilkS" user "Ref Des/Silkscreen Bottom")
		(1 "F.Mask" user "Board Geometry/Soldermask Top")
		(3 "B.Mask" user "Board Geometry/Soldermask Bottom")
		(17 "Dwgs.User" user "User.Drawings")
		(19 "Cmts.User" user "User.Comments")
		(21 "Eco1.User" user "User.Eco1")
		(23 "Eco2.User" user "User.Eco2")
		(25 "Edge.Cuts" user "Board Geometry/Outline")
		(27 "Margin" user)
		(31 "F.CrtYd" user "Package Geometry/Place Bound Top")
		(29 "B.CrtYd" user "Package Geometry/Place Bound Bottom")
		(35 "F.Fab" user "Ref Des/Assembly Top")
		(33 "B.Fab" user "Ref Des/Assembly Bottom")
	)
	(footprint ""
		(layer "F.Cu")
		(at 137.3124 -59.5884 180)
		(property "Reference" "TP52"
			(at 3.5306 0.06223 0)
			(unlocked yes)
			(layer "F.SilkS")
			(effects
				(font
					(size 0.7874 0.5842)
					(thickness 0.1524)
				)
				(justify left)
			)
		)
		(property "Value" ""
			(at 0 0 180)
			(layer "F.Fab")
			(effects
				(font
					(size 1.27 1.27)
				)
			)
		)
		(property "Device Type" "TP_PIONT-TP010CT020B030_PTH-TPA"
			(at -1.341882 0.996696 180)
			(unlocked yes)
			(layer "F.Fab")
			(hide yes)
			(effects
				(font
					(size 0.7874 0.5842)
					(thickness 0.1524)
				)
				(justify left)
			)
		)
		(duplicate_pad_numbers_are_jumpers no)
		(fp_poly
			(pts
				(arc
					(start -0.889 0)
					(mid 0.889 0)
					(end -0.889 0)
				)
			)
			(stroke
				(width 0)
				(type default)
			)
			(fill no)
			(layer "B.CrtYd")
		)
		(fp_poly
			(pts
				(arc
					(start -0.889 0)
					(mid 0.889 0)
					(end -0.889 0)
				)
			)
			(stroke
				(width 0)
				(type default)
			)
			(fill no)
			(layer "F.CrtYd")
		)
		(pad "1" thru_hole circle
			(at 0 0 180)
			(size 0.508 0.508)
			(drill 0.254)
			(layers "*.Cu" "*.Mask")
			(remove_unused_layers no)
			(net "XP12R0V")
			(clearance 0.1016)
			(padstack
				(mode front_inner_back)
				(layer "Inner"
					(shape circle)
					(size 0.508 0.508)
					(clearance 0.1016)
				)
				(layer "B.Cu"
					(shape circle)
					(size 0.762 0.762)
					(clearance -0.0254)
				)
			)
		)
	)
	(footprint ""
		(layer "F.Cu")
		(at 38.1 -127.254)
		(property "Reference" "SP74"
			(at 0 0 0)
			(layer "F.SilkS")
			(hide yes)
			(effects
				(font
					(size 1.27 1.27)
				)
			)
		)
		(property "Value" ""
			(at 0 0 0)
			(layer "F.Fab")
			(effects
				(font
					(size 1.27 1.27)
				)
			)
		)
		(duplicate_pad_numbers_are_jumpers no)
	)
	(footprint ""
		(layer "F.Cu")
		(at 89.9922 -103.5558)
		(property "Reference" "R52"
			(at 3.048 0.29337 0)
			(unlocked yes)
			(layer "F.SilkS")
			(effects
				(font
					(size 0.7874 0.5842)
					(thickness 0.1524)
				)
			)
		)
		(property "Value" "VAL*"
			(at 0.02032 2.13233 0)
			(unlocked yes)
			(layer "F.Fab")
			(hide yes)
			(effects
				(font
					(size 0.7874 0.5842)
					(thickness 0.1524)
				)
			)
		)
		(property "Tolerance" "TOL*"
			(at 0.044704 3.05435 0)
			(unlocked yes)
			(layer "Cmts.User")
			(hide yes)
			(effects
				(font
					(size 0.7874 0.5842)
					(thickness 0.1524)
				)
			)
		)
		(property "User Part Number" "PARTNUM*"
			(at 0.02032 4.024884 0)
			(unlocked yes)
			(layer "Cmts.User")
			(hide yes)
			(effects
				(font
					(size 0.7874 0.5842)
					(thickness 0.1524)
				)
			)
		)
		(property "Device Type" "RESISTOR-G155-05101-01,5.1KOHMA"
			(at 0.008382 1.210564 0)
			(unlocked yes)
			(layer "F.Fab")
			(hide yes)
			(effects
				(font
					(size 0.7874 0.5842)
					(thickness 0.1524)
				)
			)
		)
		(duplicate_pad_numbers_are_jumpers no)
		(fp_line
			(start -1.143 -0.5588)
			(end -1.143 0.5588)
			(stroke
				(width 0.1)
				(type default)
			)
			(layer "F.SilkS")
		)
		(fp_line
			(start -1.143 0.5588)
			(end 1.143 0.5588)
			(stroke
				(width 0.1)
				(type default)
			)
			(layer "F.SilkS")
		)
		(fp_line
			(start 1.143 -0.5588)
			(end -1.143 -0.5588)
			(stroke
				(width 0.1)
				(type default)
			)
			(layer "F.SilkS")
		)
		(fp_line
			(start 1.143 0.5588)
			(end 1.143 -0.5588)
			(stroke
				(width 0.1)
				(type default)
			)
			(layer "F.SilkS")
		)
		(fp_rect
			(start -1.143 0.5588)
			(end 1.143 -0.5588)
			(stroke
				(width 0)
				(type default)
			)
			(fill no)
			(layer "F.CrtYd")
		)
		(fp_line
			(start -0.508 -0.3048)
			(end -0.508 0.3048)
			(stroke
				(width 0.1)
				(type default)
			)
			(layer "F.Fab")
		)
		(fp_line
			(start -0.508 0.3048)
			(end 0.508 0.3048)
			(stroke
				(width 0.1)
				(type default)
			)
			(layer "F.Fab")
		)
		(fp_line
			(start 0.508 -0.3048)
			(end -0.508 -0.3048)
			(stroke
				(width 0.1)
				(type default)
			)
			(layer "F.Fab")
		)
		(fp_line
			(start 0.508 0.3048)
			(end 0.508 -0.3048)
			(stroke
				(width 0.1)
				(type default)
			)
			(layer "F.Fab")
		)
		(pad "1" smd rect
			(at -0.5334 0)
			(size 0.7112 0.6096)
			(layers "F.Cu" "F.Mask" "F.Paste")
			(net "XP3R3V_EN")
		)
		(pad "2" smd rect
			(at 0.5334 0)
			(size 0.7112 0.6096)
			(layers "F.Cu" "F.Mask" "F.Paste")
			(net "SG")
		)
		(zone
			(layer "F.Cu")
			(hatch none 0.5)
			(connect_pads
				(clearance 0)
			)
			(min_thickness 0.25)
			(keepout
				(tracks allowed)
				(vias not_allowed)
				(pads allowed)
				(copperpour not_allowed)
				(footprints allowed)
			)
			(placement
				(enabled no)
				(sheetname "")
			)
			(fill
				(thermal_gap 0.5)
				(thermal_bridge_width 0.5)
				(island_removal_mode 0)
			)
			(polygon
				(pts
					(xy 89.916 -103.251) (xy 90.0684 -103.251) (xy 90.0684 -103.8606) (xy 89.916 -103.8606)
				)
			)
		)
	)
	(footprint ""
		(layer "F.Cu")
		(at 108.966 -69.596)
		(property "Reference" "TP53"
			(at -0.9652 1.43637 0)
			(unlocked yes)
			(layer "F.SilkS")
			(effects
				(font
					(size 0.7874 0.5842)
					(thickness 0.1524)
				)
				(justify left)
			)
		)
		(property "Value" ""
			(at 0 0 0)
			(layer "F.Fab")
			(effects
				(font
					(size 1.27 1.27)
				)
			)
		)
		(property "Device Type" "TP_PIONT-TP010CT020B030_PTH-TPA"
			(at -1.341882 0.996696 0)
			(unlocked yes)
			(layer "F.Fab")
			(hide yes)
			(effects
				(font
					(size 0.7874 0.5842)
					(thickness 0.1524)
				)
				(justify left)
			)
		)
		(duplicate_pad_numbers_are_jumpers no)
		(fp_poly
			(pts
				(arc
					(start 0.889 0)
					(mid -0.889 0)
					(end 0.889 0)
				)
			)
			(stroke
				(width 0)
				(type default)
			)
			(fill no)
			(layer "B.CrtYd")
		)
		(fp_poly
			(pts
				(arc
					(start 0.889 0)
					(mid -0.889 0)
					(end 0.889 0)
				)
			)
			(stroke
				(width 0)
				(type default)
			)
			(fill no)
			(layer "F.CrtYd")
		)
		(pad "1" thru_hole circle
			(at 0 0)
			(size 0.508 0.508)
			(drill 0.254)
			(layers "*.Cu" "*.Mask")
			(remove_unused_layers no)
			(net "XP3R3V")
			(clearance 0.1016)
			(padstack
				(mode front_inner_back)
				(layer "Inner"
					(shape circle)
					(size 0.508 0.508)
					(clearance 0.1016)
				)
				(layer "B.Cu"
					(shape circle)
					(size 0.762 0.762)
					(clearance -0.0254)
				)
			)
		)
	)
	(footprint ""
		(layer "F.Cu")
		(at 65.532 -136.017)
		(property "Reference" "SP32"
			(at 0 0 0)
			(layer "F.SilkS")
			(hide yes)
			(effects
				(font
					(size 1.27 1.27)
				)
			)
		)
		(property "Value" ""
			(at 0 0 0)
			(layer "F.Fab")
			(effects
				(font
					(size 1.27 1.27)
				)
			)
		)
		(duplicate_pad_numbers_are_jumpers no)
	)
	(footprint ""
		(layer "F.Cu")
		(at 20.32 -27.94 180)
		(property "Reference" "R273"
			(at -2.794 -0.54737 0)
			(unlocked yes)
			(layer "F.SilkS")
			(effects
				(font
					(size 0.7874 0.5842)
					(thickness 0.1524)
				)
			)
		)
		(property "Value" "VAL*"
			(at 0.02032 2.13233 180)
			(unlocked yes)
			(layer "F.Fab")
			(hide yes)
			(effects
				(font
					(size 0.7874 0.5842)
					(thickness 0.1524)
				)
			)
		)
		(property "Device Type" "RESISTOR-G155-11000-01,100OHM,A"
			(at 0.008382 1.210564 180)
			(unlocked yes)
			(layer "F.Fab")
			(hide yes)
			(effects
				(font
					(size 0.7874 0.5842)
					(thickness 0.1524)
				)
			)
		)
		(property "User Part Number" "PARTNUM*"
			(at 0.02032 4.024884 180)
			(unlocked yes)
			(layer "Cmts.User")
			(hide yes)
			(effects
				(font
					(size 0.7874 0.5842)
					(thickness 0.1524)
				)
			)
		)
		(property "Tolerance" "TOL*"
			(at 0.044704 3.05435 180)
			(unlocked yes)
			(layer "Cmts.User")
			(hide yes)
			(effects
				(font
					(size 0.7874 0.5842)
					(thickness 0.1524)
				)
			)
		)
		(duplicate_pad_numbers_are_jumpers no)
		(fp_line
			(start 1.143 0.5588)
			(end 1.143 -0.5588)
			(stroke
				(width 0.1)
				(type default)
			)
			(layer "F.SilkS")
		)
		(fp_line
			(start 1.143 -0.5588)
			(end -1.143 -0.5588)
			(stroke
				(width 0.1)
				(type default)
			)
			(layer "F.SilkS")
		)
		(fp_line
			(start -1.143 0.5588)
			(end 1.143 0.5588)
			(stroke
				(width 0.1)
				(type default)
			)
			(layer "F.SilkS")
		)
		(fp_line
			(start -1.143 -0.5588)
			(end -1.143 0.5588)
			(stroke
				(width 0.1)
				(type default)
			)
			(layer "F.SilkS")
		)
		(fp_poly
			(pts
				(xy -1.143 0.5588) (xy 1.143 0.5588) (xy 1.143 -0.5588) (xy -1.143 -0.5588)
			)
			(stroke
				(width 0)
				(type default)
			)
			(fill no)
			(layer "F.CrtYd")
		)
		(fp_line
			(start 0.508 0.3048)
			(end 0.508 -0.3048)
			(stroke
				(width 0.1)
				(type default)
			)
			(layer "F.Fab")
		)
		(fp_line
			(start 0.508 -0.3048)
			(end -0.508 -0.3048)
			(stroke
				(width 0.1)
				(type default)
			)
			(layer "F.Fab")
		)
		(fp_line
			(start -0.508 0.3048)
			(end 0.508 0.3048)
			(stroke
				(width 0.1)
				(type default)
			)
			(layer "F.Fab")
		)
		(fp_line
			(start -0.508 -0.3048)
			(end -0.508 0.3048)
			(stroke
				(width 0.1)
				(type default)
			)
			(layer "F.Fab")
		)
		(pad "1" smd rect
			(at -0.5334 0 180)
			(size 0.7112 0.6096)
			(layers "F.Cu" "F.Mask" "F.Paste")
			(net "FPGA_OUT_SMA2_LED_BLUE_N")
		)
		(pad "2" smd rect
			(at 0.5334 0 180)
			(size 0.7112 0.6096)
			(layers "F.Cu" "F.Mask" "F.Paste")
			(net "UNNAMED_14_LED4PV14_I266_1")
		)
		(zone
			(layer "F.Cu")
			(hatch none 0.5)
			(connect_pads
				(clearance 0)
			)
			(min_thickness 0.25)
			(keepout
				(tracks not_allowed)
				(vias allowed)
				(pads allowed)
				(copperpour not_allowed)
				(footprints allowed)
			)
			(placement
				(enabled no)
				(sheetname "")
			)
			(fill
				(thermal_gap 0.5)
				(thermal_bridge_width 0.5)
				(island_removal_mode 0)
			)
			(polygon
				(pts
					(xy 20.3962 -28.2448) (xy 20.2438 -28.2448) (xy 20.2438 -27.6352) (xy 20.3962 -27.6352)
				)
			)
		)
		(zone
			(layer "F.Cu")
			(hatch none 0.5)
			(connect_pads
				(clearance 0)
			)
			(min_thickness 0.25)
			(keepout
				(tracks allowed)
				(vias not_allowed)
				(pads allowed)
				(copperpour not_allowed)
				(footprints allowed)
			)
			(placement
				(enabled no)
				(sheetname "")
			)
			(fill
				(thermal_gap 0.5)
				(thermal_bridge_width 0.5)
				(island_removal_mode 0)
			)
			(polygon
				(pts
					(xy 20.3962 -28.2448) (xy 20.2438 -28.2448) (xy 20.2438 -27.6352) (xy 20.3962 -27.6352)
				)
			)
		)
	)
	(footprint ""
		(layer "F.Cu")
		(at 134.112 -69.215)
		(property "Reference" "C193"
			(at 0.889 -3.38963 0)
			(unlocked yes)
			(layer "F.SilkS")
			(effects
				(font
					(size 0.7874 0.5842)
					(thickness 0.1524)
				)
			)
		)
		(property "Value" "VAL*"
			(at 0.193548 2.13614 0)
			(unlocked yes)
			(layer "F.Fab")
			(hide yes)
			(effects
				(font
					(size 0.7874 0.5842)
					(thickness 0.1524)
				)
			)
		)
		(property "Tolerance" "TOL*"
			(at 0.216154 3.1496 0)
			(unlocked yes)
			(layer "Cmts.User")
			(hide yes)
			(effects
				(font
					(size 0.7874 0.5842)
					(thickness 0.1524)
				)
			)
		)
		(property "Device Type" "CAPACITOR-G104-0B103-EK,0.01UFA"
			(at 0.184404 1.180592 0)
			(unlocked yes)
			(layer "F.Fab")
			(hide yes)
			(effects
				(font
					(size 0.7874 0.5842)
					(thickness 0.1524)
				)
			)
		)
		(property "User Part Number" "PARTNUM*"
			(at 0.216154 4.185666 0)
			(unlocked yes)
			(layer "Cmts.User")
			(hide yes)
			(effects
				(font
					(size 0.7874 0.5842)
					(thickness 0.1524)
				)
			)
		)
		(duplicate_pad_numbers_are_jumpers no)
		(fp_line
			(start -0.671322 -0.4445)
			(end 0.671322 -0.4445)
			(stroke
				(width 0.1)
				(type default)
			)
			(layer "F.SilkS")
		)
		(fp_line
			(start -0.671322 0.4445)
			(end -0.671322 -0.4445)
			(stroke
				(width 0.1)
				(type default)
			)
			(layer "F.SilkS")
		)
		(fp_line
			(start 0.671322 -0.4445)
			(end 0.671322 0.4445)
			(stroke
				(width 0.1)
				(type default)
			)
			(layer "F.SilkS")
		)
		(fp_line
			(start 0.671322 0.4445)
			(end -0.671322 0.4445)
			(stroke
				(width 0.1)
				(type default)
			)
			(layer "F.SilkS")
		)
		(fp_rect
			(start 0.671322 0.4445)
			(end -0.671322 -0.4445)
			(stroke
				(width 0)
				(type default)
			)
			(fill no)
			(layer "F.CrtYd")
		)
		(fp_line
			(start -0.31496 -0.1651)
			(end -0.31496 0.1651)
			(stroke
				(width 0.1)
				(type default)
			)
			(layer "F.Fab")
		)
		(fp_line
			(start -0.31496 0.1651)
			(end 0.31496 0.1651)
			(stroke
				(width 0.1)
				(type default)
			)
			(layer "F.Fab")
		)
		(fp_line
			(start 0.31496 -0.1651)
			(end -0.31496 -0.1651)
			(stroke
				(width 0.1)
				(type default)
			)
			(layer "F.Fab")
		)
		(fp_line
			(start 0.31496 0.1651)
			(end 0.31496 -0.1651)
			(stroke
				(width 0.1)
				(type default)
			)
			(layer "F.Fab")
		)
		(pad "1" smd rect
			(at -0.264922 0)
			(size 0.3048 0.381)
			(layers "F.Cu" "F.Mask" "F.Paste")
			(net "XP1R8V_PG_R")
		)
		(pad "2" smd rect
			(at 0.264922 0)
			(size 0.3048 0.381)
			(layers "F.Cu" "F.Mask" "F.Paste")
			(net "SG")
		)
		(zone
			(layer "F.Cu")
			(hatch none 0.5)
			(connect_pads
				(clearance 0)
			)
			(min_thickness 0.25)
			(keepout
				(tracks allowed)
				(vias not_allowed)
				(pads allowed)
				(copperpour not_allowed)
				(footprints allowed)
			)
			(placement
				(enabled no)
				(sheetname "")
			)
			(fill
				(thermal_gap 0.5)
				(thermal_bridge_width 0.5)
				(island_removal_mode 0)
			)
			(polygon
				(pts
					(xy 134.224522 -69.0245) (xy 134.224522 -69.4055) (xy 133.999478 -69.4055) (xy 133.999478 -69.0245)
				)
			)
		)
	)
	(footprint ""
		(layer "F.Cu")
		(at 38.354 -80.899 90)
		(property "Reference" "C309"
			(at 3.556 -0.08763 90)
			(unlocked yes)
			(layer "F.SilkS")
			(effects
				(font
					(size 0.7874 0.5842)
					(thickness 0.1524)
				)
			)
		)
		(property "Value" "VAL*"
			(at 0.0762 2.067306 90)
			(unlocked yes)
			(layer "F.Fab")
			(hide yes)
			(effects
				(font
					(size 0.7874 0.5842)
					(thickness 0.1524)
				)
			)
		)
		(property "Tolerance" "TOL*"
			(at 0.0762 3.032506 90)
			(unlocked yes)
			(layer "Cmts.User")
			(hide yes)
			(effects
				(font
					(size 0.7874 0.5842)
					(thickness 0.1524)
				)
			)
		)
		(property "User Part Number" "PARTNUM*"
			(at 0.1016 4.023106 90)
			(unlocked yes)
			(layer "Cmts.User")
			(hide yes)
			(effects
				(font
					(size 0.7874 0.5842)
					(thickness 0.1524)
				)
			)
		)
		(property "Device Type" "CAPACITOR-G105-0B104-EK,0.1UF,A"
			(at 0.0508 1.127506 90)
			(unlocked yes)
			(layer "F.Fab")
			(hide yes)
			(effects
				(font
					(size 0.7874 0.5842)
					(thickness 0.1524)
				)
			)
		)
		(duplicate_pad_numbers_are_jumpers no)
		(fp_line
			(start 1.143 -0.5588)
			(end -1.143 -0.5588)
			(stroke
				(width 0.1)
				(type default)
			)
			(layer "F.SilkS")
		)
		(fp_line
			(start -1.143 -0.5588)
			(end -1.143 0.5588)
			(stroke
				(width 0.1)
				(type default)
			)
			(layer "F.SilkS")
		)
		(fp_line
			(start 1.143 0.5588)
			(end 1.143 -0.5588)
			(stroke
				(width 0.1)
				(type default)
			)
			(layer "F.SilkS")
		)
		(fp_line
			(start -1.143 0.5588)
			(end 1.143 0.5588)
			(stroke
				(width 0.1)
				(type default)
			)
			(layer "F.SilkS")
		)
		(fp_poly
			(pts
				(xy -1.143 0.5588) (xy 1.143 0.5588) (xy 1.143 -0.5588) (xy -1.143 -0.5588)
			)
			(stroke
				(width 0)
				(type default)
			)
			(fill no)
			(layer "F.CrtYd")
		)
		(fp_line
			(start 0.508 -0.3048)
			(end -0.508 -0.3048)
			(stroke
				(width 0.1)
				(type default)
			)
			(layer "F.Fab")
		)
		(fp_line
			(start -0.508 -0.3048)
			(end -0.508 0.3048)
			(stroke
				(width 0.1)
				(type default)
			)
			(layer "F.Fab")
		)
		(fp_line
			(start 0.508 0.3048)
			(end 0.508 -0.3048)
			(stroke
				(width 0.1)
				(type default)
			)
			(layer "F.Fab")
		)
		(fp_line
			(start -0.508 0.3048)
			(end 0.508 0.3048)
			(stroke
				(width 0.1)
				(type default)
			)
			(layer "F.Fab")
		)
		(pad "1" smd rect
			(at -0.5334 0 90)
			(size 0.7112 0.6096)
			(layers "F.Cu" "F.Mask" "F.Paste")
			(net "XP3R3V_FT4232")
		)
		(pad "2" smd rect
			(at 0.5334 0 90)
			(size 0.7112 0.6096)
			(layers "F.Cu" "F.Mask" "F.Paste")
			(net "SG")
		)
		(zone
			(layer "F.Cu")
			(hatch none 0.5)
			(connect_pads
				(clearance 0)
			)
			(min_thickness 0.25)
			(keepout
				(tracks not_allowed)
				(vias allowed)
				(pads allowed)
				(copperpour not_allowed)
				(footprints allowed)
			)
			(placement
				(enabled no)
				(sheetname "")
			)
			(fill
				(thermal_gap 0.5)
				(thermal_bridge_width 0.5)
				(island_removal_mode 0)
			)
			(polygon
				(pts
					(xy 38.6588 -80.8228) (xy 38.6588 -80.9752) (xy 38.0492 -80.9752) (xy 38.0492 -80.8228)
				)
			)
		)
		(zone
			(layer "F.Cu")
			(hatch none 0.5)
			(connect_pads
				(clearance 0)
			)
			(min_thickness 0.25)
			(keepout
				(tracks allowed)
				(vias not_allowed)
				(pads allowed)
				(copperpour not_allowed)
				(footprints allowed)
			)
			(placement
				(enabled no)
				(sheetname "")
			)
			(fill
				(thermal_gap 0.5)
				(thermal_bridge_width 0.5)
				(island_removal_mode 0)
			)
			(polygon
				(pts
					(xy 38.6588 -80.8228) (xy 38.6588 -80.9752) (xy 38.0492 -80.9752) (xy 38.0492 -80.8228)
				)
			)
		)
	)
	(footprint ""
		(layer "F.Cu")
		(at 57.15 -134.747)
		(property "Reference" "SP46"
			(at 0 0 0)
			(layer "F.SilkS")
			(hide yes)
			(effects
				(font
					(size 1.27 1.27)
				)
			)
		)
		(property "Value" ""
			(at 0 0 0)
			(layer "F.Fab")
			(effects
				(font
					(size 1.27 1.27)
				)
			)
		)
		(duplicate_pad_numbers_are_jumpers no)
	)
)
